(kicad_pcb
	(version 20260206)
	(generator "pcbnew")
	(generator_version "10.0")
	(general
		(thickness 1.6)
		(legacy_teardrops no)
	)
	(paper "A4")
	(title_block
		(title "01162023_DA0F0TEBIF0_F0T_Expander_BD_F_brd_V02_OCP.brd")
		(comment 1 "Grand Teton / footprints 1636-1641 of 9728")
	)
	(layers
		(0 "F.Cu" signal "TOP")
		(4 "In1.Cu" signal "GND")
		(6 "In2.Cu" signal "VCC")
		(8 "In3.Cu" signal "VCC1")
		(10 "In4.Cu" signal "GND1")
		(12 "In5.Cu" signal "IN1")
		(14 "In6.Cu" signal "GND2")
		(16 "In7.Cu" signal "IN2")
		(18 "In8.Cu" signal "GND3")
		(20 "In9.Cu" signal "IN3")
		(22 "In10.Cu" signal "GND4")
		(24 "In11.Cu" signal "IN4")
		(26 "In12.Cu" signal "GND5")
		(28 "In13.Cu" signal "IN5")
		(30 "In14.Cu" signal "GND6")
		(32 "In15.Cu" signal "IN6")
		(34 "In16.Cu" signal "GND7")
		(2 "B.Cu" signal "BOTTOM")
		(9 "F.Adhes" user "F.Adhesive")
		(11 "B.Adhes" user "B.Adhesive")
		(13 "F.Paste" user "Package Geometry/Pastemask Top")
		(15 "B.Paste" user "Package Geometry/Pastemask Bottom")
		(5 "F.SilkS" user "Ref Des/Silkscreen Top")
		(7 "B.SilkS" user "Ref Des/Silkscreen Bottom")
		(1 "F.Mask" user "Board Geometry/Soldermask Top")
		(3 "B.Mask" user "Board Geometry/Soldermask Bottom")
		(17 "Dwgs.User" user "User.Drawings")
		(19 "Cmts.User" user "User.Comments")
		(21 "Eco1.User" user "User.Eco1")
		(23 "Eco2.User" user "User.Eco2")
		(25 "Edge.Cuts" user "Board Geometry/Outline")
		(27 "Margin" user)
		(31 "F.CrtYd" user "Package Geometry/Place Bound Top")
		(29 "B.CrtYd" user "Package Geometry/Place Bound Bottom")
		(35 "F.Fab" user "Ref Des/Assembly Top")
		(33 "B.Fab" user "Ref Des/Assembly Bottom")
	)
	(footprint ""
		(layer "F.Cu")
		(at 245.634764 -133.088126 180)
		(property "Reference" "PC343"
			(at 0 0 180)
			(layer "F.SilkS")
			(hide yes)
			(effects
				(font
					(size 1.27 1.27)
				)
			)
		)
		(property "Value" ""
			(at 0 0 180)
			(layer "F.Fab")
			(effects
				(font
					(size 1.27 1.27)
				)
			)
		)
		(duplicate_pad_numbers_are_jumpers no)
		(fp_line
			(start 1.524 0.762)
			(end -1.524 0.762)
			(stroke
				(width 0.1524)
				(type default)
			)
			(layer "F.SilkS")
		)
		(fp_line
			(start 1.524 -0.762)
			(end 1.524 0.762)
			(stroke
				(width 0.1524)
				(type default)
			)
			(layer "F.SilkS")
		)
		(fp_line
			(start -1.524 0.762)
			(end -1.524 -0.762)
			(stroke
				(width 0.1524)
				(type default)
			)
			(layer "F.SilkS")
		)
		(fp_line
			(start -1.524 -0.762)
			(end 1.524 -0.762)
			(stroke
				(width 0.1524)
				(type default)
			)
			(layer "F.SilkS")
		)
		(fp_line
			(start 1.1049 0.724916)
			(end 1.1049 -0.724916)
			(stroke
				(width 0.1)
				(type default)
			)
			(layer "F.Fab")
		)
		(fp_line
			(start 1.1049 -0.724916)
			(end -1.1049 -0.724916)
			(stroke
				(width 0.1)
				(type default)
			)
			(layer "F.Fab")
		)
		(fp_line
			(start -1.1049 0.724916)
			(end 1.1049 0.724916)
			(stroke
				(width 0.1)
				(type default)
			)
			(layer "F.Fab")
		)
		(fp_line
			(start -1.1049 -0.724916)
			(end -1.1049 0.724916)
			(stroke
				(width 0.1)
				(type default)
			)
			(layer "F.Fab")
		)
		(pad "1" smd rect
			(at -0.889 0)
			(size 1.016 1.27)
			(layers "F.Cu" "F.Mask" "F.Paste")
			(net "GND")
		)
		(pad "2" smd rect
			(at 0.889 0)
			(size 1.016 1.27)
			(layers "F.Cu" "F.Mask" "F.Paste")
			(net "P12V_AUX")
		)
	)
	(footprint ""
		(layer "F.Cu")
		(at 26.267918 -51.019456)
		(property "Reference" "PC362"
			(at 0 0 0)
			(layer "F.SilkS")
			(hide yes)
			(effects
				(font
					(size 1.27 1.27)
				)
			)
		)
		(property "Value" ""
			(at 0 0 0)
			(layer "F.Fab")
			(effects
				(font
					(size 1.27 1.27)
				)
			)
		)
		(duplicate_pad_numbers_are_jumpers no)
		(fp_line
			(start -0.7874 -0.4064)
			(end 0.7874 -0.4064)
			(stroke
				(width 0.1524)
				(type default)
			)
			(layer "F.SilkS")
		)
		(fp_line
			(start -0.7874 0.4064)
			(end -0.7874 -0.4064)
			(stroke
				(width 0.1524)
				(type default)
			)
			(layer "F.SilkS")
		)
		(fp_line
			(start 0.7874 -0.4064)
			(end 0.7874 0.4064)
			(stroke
				(width 0.1524)
				(type default)
			)
			(layer "F.SilkS")
		)
		(fp_line
			(start 0.7874 0.4064)
			(end -0.7874 0.4064)
			(stroke
				(width 0.1524)
				(type default)
			)
			(layer "F.SilkS")
		)
		(fp_line
			(start -0.67945 -0.305054)
			(end -0.12065 -0.305054)
			(stroke
				(width 0.1)
				(type default)
			)
			(layer "F.Fab")
		)
		(fp_line
			(start -0.67945 0.3048)
			(end -0.67945 -0.305054)
			(stroke
				(width 0.1)
				(type default)
			)
			(layer "F.Fab")
		)
		(fp_line
			(start -0.12065 -0.305054)
			(end -0.12065 -0.2794)
			(stroke
				(width 0.1)
				(type default)
			)
			(layer "F.Fab")
		)
		(fp_line
			(start -0.12065 -0.2794)
			(end 0.12065 -0.2794)
			(stroke
				(width 0.1)
				(type default)
			)
			(layer "F.Fab")
		)
		(fp_line
			(start -0.12065 0.2794)
			(end -0.12065 0.3048)
			(stroke
				(width 0.1)
				(type default)
			)
			(layer "F.Fab")
		)
		(fp_line
			(start -0.12065 0.3048)
			(end -0.67945 0.3048)
			(stroke
				(width 0.1)
				(type default)
			)
			(layer "F.Fab")
		)
		(fp_line
			(start 0.120396 0.2794)
			(end -0.12065 0.2794)
			(stroke
				(width 0.1)
				(type default)
			)
			(layer "F.Fab")
		)
		(fp_line
			(start 0.120396 0.3048)
			(end 0.120396 0.2794)
			(stroke
				(width 0.1)
				(type default)
			)
			(layer "F.Fab")
		)
		(fp_line
			(start 0.12065 -0.3048)
			(end 0.67945 -0.3048)
			(stroke
				(width 0.1)
				(type default)
			)
			(layer "F.Fab")
		)
		(fp_line
			(start 0.12065 -0.2794)
			(end 0.12065 -0.3048)
			(stroke
				(width 0.1)
				(type default)
			)
			(layer "F.Fab")
		)
		(fp_line
			(start 0.67945 -0.3048)
			(end 0.67945 0.3048)
			(stroke
				(width 0.1)
				(type default)
			)
			(layer "F.Fab")
		)
		(fp_line
			(start 0.67945 0.3048)
			(end 0.120396 0.3048)
			(stroke
				(width 0.1)
				(type default)
			)
			(layer "F.Fab")
		)
		(pad "1" smd circle
			(at -0.40005 0)
			(size 0 0)
			(layers "F.Cu" "F.Mask" "F.Paste")
			(net "P12V_SSD0_SS")
		)
		(pad "2" smd circle
			(at 0.40005 0)
			(size 0 0)
			(layers "F.Cu" "F.Mask" "F.Paste")
			(net "GND")
		)
	)
	(footprint ""
		(layer "F.Cu")
		(at 430.966118 -77.889608 180)
		(property "Reference" "C957"
			(at 0 0 180)
			(layer "F.SilkS")
			(hide yes)
			(effects
				(font
					(size 1.27 1.27)
				)
			)
		)
		(property "Value" ""
			(at 0 0 180)
			(layer "F.Fab")
			(effects
				(font
					(size 1.27 1.27)
				)
			)
		)
		(duplicate_pad_numbers_are_jumpers no)
		(fp_line
			(start 0.7874 0.4064)
			(end -0.7874 0.4064)
			(stroke
				(width 0.1524)
				(type default)
			)
			(layer "F.SilkS")
		)
		(fp_line
			(start 0.7874 -0.4064)
			(end 0.7874 0.4064)
			(stroke
				(width 0.1524)
				(type default)
			)
			(layer "F.SilkS")
		)
		(fp_line
			(start -0.7874 0.4064)
			(end -0.7874 -0.4064)
			(stroke
				(width 0.1524)
				(type default)
			)
			(layer "F.SilkS")
		)
		(fp_line
			(start -0.7874 -0.4064)
			(end 0.7874 -0.4064)
			(stroke
				(width 0.1524)
				(type default)
			)
			(layer "F.SilkS")
		)
		(fp_line
			(start 0.67945 0.3048)
			(end 0.120396 0.3048)
			(stroke
				(width 0.1)
				(type default)
			)
			(layer "F.Fab")
		)
		(fp_line
			(start 0.67945 -0.3048)
			(end 0.67945 0.3048)
			(stroke
				(width 0.1)
				(type default)
			)
			(layer "F.Fab")
		)
		(fp_line
			(start 0.12065 -0.2794)
			(end 0.12065 -0.3048)
			(stroke
				(width 0.1)
				(type default)
			)
			(layer "F.Fab")
		)
		(fp_line
			(start 0.12065 -0.3048)
			(end 0.67945 -0.3048)
			(stroke
				(width 0.1)
				(type default)
			)
			(layer "F.Fab")
		)
		(fp_line
			(start 0.120396 0.3048)
			(end 0.120396 0.2794)
			(stroke
				(width 0.1)
				(type default)
			)
			(layer "F.Fab")
		)
		(fp_line
			(start 0.120396 0.2794)
			(end -0.12065 0.2794)
			(stroke
				(width 0.1)
				(type default)
			)
			(layer "F.Fab")
		)
		(fp_line
			(start -0.12065 0.3048)
			(end -0.67945 0.3048)
			(stroke
				(width 0.1)
				(type default)
			)
			(layer "F.Fab")
		)
		(fp_line
			(start -0.12065 0.2794)
			(end -0.12065 0.3048)
			(stroke
				(width 0.1)
				(type default)
			)
			(layer "F.Fab")
		)
		(fp_line
			(start -0.12065 -0.2794)
			(end 0.12065 -0.2794)
			(stroke
				(width 0.1)
				(type default)
			)
			(layer "F.Fab")
		)
		(fp_line
			(start -0.12065 -0.305054)
			(end -0.12065 -0.2794)
			(stroke
				(width 0.1)
				(type default)
			)
			(layer "F.Fab")
		)
		(fp_line
			(start -0.67945 0.3048)
			(end -0.67945 -0.305054)
			(stroke
				(width 0.1)
				(type default)
			)
			(layer "F.Fab")
		)
		(fp_line
			(start -0.67945 -0.305054)
			(end -0.12065 -0.305054)
			(stroke
				(width 0.1)
				(type default)
			)
			(layer "F.Fab")
		)
		(pad "1" smd circle
			(at -0.40005 0 180)
			(size 0 0)
			(layers "F.Cu" "F.Mask" "F.Paste")
			(net "P3V3_NIC7")
		)
		(pad "2" smd circle
			(at 0.40005 0 180)
			(size 0 0)
			(layers "F.Cu" "F.Mask" "F.Paste")
			(net "GND")
		)
	)
	(footprint ""
		(layer "F.Cu")
		(at 89.214452 -311.227978 135)
		(property "Reference" "R1240"
			(at 0 0 135)
			(layer "F.SilkS")
			(hide yes)
			(effects
				(font
					(size 1.27 1.27)
				)
			)
		)
		(property "Value" ""
			(at 0 0 135)
			(layer "F.Fab")
			(effects
				(font
					(size 1.27 1.27)
				)
			)
		)
		(duplicate_pad_numbers_are_jumpers no)
		(fp_line
			(start 0.787389 -0.406267)
			(end 0.787389 0.406267)
			(stroke
				(width 0.1524)
				(type default)
			)
			(layer "F.SilkS")
		)
		(fp_line
			(start 0.787389 0.406267)
			(end -0.787389 0.406267)
			(stroke
				(width 0.1524)
				(type default)
			)
			(layer "F.SilkS")
		)
		(fp_line
			(start -0.787389 -0.406267)
			(end 0.787389 -0.406267)
			(stroke
				(width 0.1524)
				(type default)
			)
			(layer "F.SilkS")
		)
		(fp_line
			(start -0.787389 0.406267)
			(end -0.787389 -0.406267)
			(stroke
				(width 0.1524)
				(type default)
			)
			(layer "F.SilkS")
		)
		(fp_line
			(start 0.679446 -0.30479)
			(end 0.679446 0.30479)
			(stroke
				(width 0.1)
				(type default)
			)
			(layer "F.Fab")
		)
		(fp_line
			(start 0.120515 -0.30479)
			(end 0.679446 -0.30479)
			(stroke
				(width 0.1)
				(type default)
			)
			(layer "F.Fab")
		)
		(fp_line
			(start 0.120695 -0.279466)
			(end 0.120515 -0.30479)
			(stroke
				(width 0.1)
				(type default)
			)
			(layer "F.Fab")
		)
		(fp_line
			(start 0.679446 0.30479)
			(end 0.120515 0.30479)
			(stroke
				(width 0.1)
				(type default)
			)
			(layer "F.Fab")
		)
		(fp_line
			(start -0.120695 -0.304969)
			(end -0.120695 -0.279466)
			(stroke
				(width 0.1)
				(type default)
			)
			(layer "F.Fab")
		)
		(fp_line
			(start -0.120695 -0.279466)
			(end 0.120695 -0.279466)
			(stroke
				(width 0.1)
				(type default)
			)
			(layer "F.Fab")
		)
		(fp_line
			(start 0.120335 0.279466)
			(end -0.120695 0.279466)
			(stroke
				(width 0.1)
				(type default)
			)
			(layer "F.Fab")
		)
		(fp_line
			(start 0.120515 0.30479)
			(end 0.120335 0.279466)
			(stroke
				(width 0.1)
				(type default)
			)
			(layer "F.Fab")
		)
		(fp_line
			(start -0.679446 -0.305149)
			(end -0.120695 -0.304969)
			(stroke
				(width 0.1)
				(type default)
			)
			(layer "F.Fab")
		)
		(fp_line
			(start -0.120695 0.279466)
			(end -0.120515 0.30479)
			(stroke
				(width 0.1)
				(type default)
			)
			(layer "F.Fab")
		)
		(fp_line
			(start -0.120515 0.30479)
			(end -0.679446 0.30479)
			(stroke
				(width 0.1)
				(type default)
			)
			(layer "F.Fab")
		)
		(fp_line
			(start -0.679446 0.30479)
			(end -0.679446 -0.305149)
			(stroke
				(width 0.1)
				(type default)
			)
			(layer "F.Fab")
		)
		(pad "1" smd circle
			(at -0.40005 0 135)
			(size 0 0)
			(layers "F.Cu" "F.Mask" "F.Paste")
			(net "PEX0_SPARE0")
		)
		(pad "2" smd circle
			(at 0.40005 0 135)
			(size 0 0)
			(layers "F.Cu" "F.Mask" "F.Paste")
			(net "P1V8_PEX")
		)
	)
	(footprint ""
		(layer "F.Cu")
		(at 145.983706 -61.487812 180)
		(property "Reference" "R5975"
			(at 0 0 180)
			(layer "F.SilkS")
			(hide yes)
			(effects
				(font
					(size 1.27 1.27)
				)
			)
		)
		(property "Value" ""
			(at 0 0 180)
			(layer "F.Fab")
			(effects
				(font
					(size 1.27 1.27)
				)
			)
		)
		(duplicate_pad_numbers_are_jumpers no)
		(fp_line
			(start 0.7874 0.4064)
			(end -0.7874 0.4064)
			(stroke
				(width 0.1524)
				(type default)
			)
			(layer "F.SilkS")
		)
		(fp_line
			(start 0.7874 -0.4064)
			(end 0.7874 0.4064)
			(stroke
				(width 0.1524)
				(type default)
			)
			(layer "F.SilkS")
		)
		(fp_line
			(start -0.7874 0.4064)
			(end -0.7874 -0.4064)
			(stroke
				(width 0.1524)
				(type default)
			)
			(layer "F.SilkS")
		)
		(fp_line
			(start -0.7874 -0.4064)
			(end 0.7874 -0.4064)
			(stroke
				(width 0.1524)
				(type default)
			)
			(layer "F.SilkS")
		)
		(fp_line
			(start 0.67945 0.3048)
			(end 0.120396 0.3048)
			(stroke
				(width 0.1)
				(type default)
			)
			(layer "F.Fab")
		)
		(fp_line
			(start 0.67945 -0.3048)
			(end 0.67945 0.3048)
			(stroke
				(width 0.1)
				(type default)
			)
			(layer "F.Fab")
		)
		(fp_line
			(start 0.12065 -0.2794)
			(end 0.12065 -0.3048)
			(stroke
				(width 0.1)
				(type default)
			)
			(layer "F.Fab")
		)
		(fp_line
			(start 0.12065 -0.3048)
			(end 0.67945 -0.3048)
			(stroke
				(width 0.1)
				(type default)
			)
			(layer "F.Fab")
		)
		(fp_line
			(start 0.120396 0.3048)
			(end 0.120396 0.2794)
			(stroke
				(width 0.1)
				(type default)
			)
			(layer "F.Fab")
		)
		(fp_line
			(start 0.120396 0.2794)
			(end -0.12065 0.2794)
			(stroke
				(width 0.1)
				(type default)
			)
			(layer "F.Fab")
		)
		(fp_line
			(start -0.12065 0.3048)
			(end -0.67945 0.3048)
			(stroke
				(width 0.1)
				(type default)
			)
			(layer "F.Fab")
		)
		(fp_line
			(start -0.12065 0.2794)
			(end -0.12065 0.3048)
			(stroke
				(width 0.1)
				(type default)
			)
			(layer "F.Fab")
		)
		(fp_line
			(start -0.12065 -0.2794)
			(end 0.12065 -0.2794)
			(stroke
				(width 0.1)
				(type default)
			)
			(layer "F.Fab")
		)
		(fp_line
			(start -0.12065 -0.305054)
			(end -0.12065 -0.2794)
			(stroke
				(width 0.1)
				(type default)
			)
			(layer "F.Fab")
		)
		(fp_line
			(start -0.67945 0.3048)
			(end -0.67945 -0.305054)
			(stroke
				(width 0.1)
				(type default)
			)
			(layer "F.Fab")
		)
		(fp_line
			(start -0.67945 -0.305054)
			(end -0.12065 -0.305054)
			(stroke
				(width 0.1)
				(type default)
			)
			(layer "F.Fab")
		)
		(pad "1" smd circle
			(at -0.40005 0 180)
			(size 0 0)
			(layers "F.Cu" "F.Mask" "F.Paste")
			(net "PWRGD_P12V_SSD5_D")
		)
		(pad "2" smd circle
			(at 0.40005 0 180)
			(size 0 0)
			(layers "F.Cu" "F.Mask" "F.Paste")
			(net "PWRGD_P12V_SSD5_R")
		)
	)
	(footprint ""
		(layer "F.Cu")
		(at 71.49846 -66.32194 -90)
		(property "Reference" "PC652"
			(at 0 0 270)
			(layer "F.SilkS")
			(hide yes)
			(effects
				(font
					(size 1.27 1.27)
				)
			)
		)
		(property "Value" ""
			(at 0 0 270)
			(layer "F.Fab")
			(effects
				(font
					(size 1.27 1.27)
				)
			)
		)
		(duplicate_pad_numbers_are_jumpers no)
		(fp_line
			(start -0.7874 0.4064)
			(end -0.7874 -0.4064)
			(stroke
				(width 0.1524)
				(type default)
			)
			(layer "F.SilkS")
		)
		(fp_line
			(start 0.7874 0.4064)
			(end -0.7874 0.4064)
			(stroke
				(width 0.1524)
				(type default)
			)
			(layer "F.SilkS")
		)
		(fp_line
			(start -0.7874 -0.4064)
			(end 0.7874 -0.4064)
			(stroke
				(width 0.1524)
				(type default)
			)
			(layer "F.SilkS")
		)
		(fp_line
			(start 0.7874 -0.4064)
			(end 0.7874 0.4064)
			(stroke
				(width 0.1524)
				(type default)
			)
			(layer "F.SilkS")
		)
		(fp_line
			(start -0.67945 0.3048)
			(end -0.67945 -0.305054)
			(stroke
				(width 0.1)
				(type default)
			)
			(layer "F.Fab")
		)
		(fp_line
			(start -0.12065 0.3048)
			(end -0.67945 0.3048)
			(stroke
				(width 0.1)
				(type default)
			)
			(layer "F.Fab")
		)
		(fp_line
			(start 0.120396 0.3048)
			(end 0.120396 0.2794)
			(stroke
				(width 0.1)
				(type default)
			)
			(layer "F.Fab")
		)
		(fp_line
			(start 0.67945 0.3048)
			(end 0.120396 0.3048)
			(stroke
				(width 0.1)
				(type default)
			)
			(layer "F.Fab")
		)
		(fp_line
			(start -0.12065 0.2794)
			(end -0.12065 0.3048)
			(stroke
				(width 0.1)
				(type default)
			)
			(layer "F.Fab")
		)
		(fp_line
			(start 0.120396 0.2794)
			(end -0.12065 0.2794)
			(stroke
				(width 0.1)
				(type default)
			)
			(layer "F.Fab")
		)
		(fp_line
			(start -0.12065 -0.2794)
			(end 0.12065 -0.2794)
			(stroke
				(width 0.1)
				(type default)
			)
			(layer "F.Fab")
		)
		(fp_line
			(start 0.12065 -0.2794)
			(end 0.12065 -0.3048)
			(stroke
				(width 0.1)
				(type default)
			)
			(layer "F.Fab")
		)
		(fp_line
			(start 0.12065 -0.3048)
			(end 0.67945 -0.3048)
			(stroke
				(width 0.1)
				(type default)
			)
			(layer "F.Fab")
		)
		(fp_line
			(start 0.67945 -0.3048)
			(end 0.67945 0.3048)
			(stroke
				(width 0.1)
				(type default)
			)
			(layer "F.Fab")
		)
		(fp_line
			(start -0.67945 -0.305054)
			(end -0.12065 -0.305054)
			(stroke
				(width 0.1)
				(type default)
			)
			(layer "F.Fab")
		)
		(fp_line
			(start -0.12065 -0.305054)
			(end -0.12065 -0.2794)
			(stroke
				(width 0.1)
				(type default)
			)
			(layer "F.Fab")
		)
		(pad "1" smd circle
			(at -0.40005 0 270)
			(size 0 0)
			(layers "F.Cu" "F.Mask" "F.Paste")
			(net "P12V_SSD2_CO_GATE")
		)
		(pad "2" smd circle
			(at 0.40005 0 270)
			(size 0 0)
			(layers "F.Cu" "F.Mask" "F.Paste")
			(net "GND")
		)
	)
)
